(kicad_pcb
	(version 20260206)
	(generator "pcbnew")
	(generator_version "10.0")
	(general
		(thickness 1.6)
		(legacy_teardrops no)
	)
	(paper "A4")
	(title_block
		(title "baseboard — 13948-1b.1110WZS1818.brd")
		(comment 1 "Honey Badger (Wiwynn) / footprint 1078 of 2523 (SU1), pads 583-672 of 672")
	)
	(layers
		(0 "F.Cu" signal "TOP")
		(4 "In1.Cu" signal "L2GND")
		(6 "In2.Cu" signal "L3")
		(8 "In3.Cu" signal "L4VCC")
		(10 "In4.Cu" signal "L5VCC")
		(12 "In5.Cu" signal "L6")
		(14 "In6.Cu" signal "L7GND")
		(2 "B.Cu" signal "BOTTOM")
		(9 "F.Adhes" user "F.Adhesive")
		(11 "B.Adhes" user "B.Adhesive")
		(13 "F.Paste" user "Package Geometry/Pastemask Top")
		(15 "B.Paste" user "Package Geometry/Pastemask Bottom")
		(5 "F.SilkS" user "Ref Des/Silkscreen Top")
		(7 "B.SilkS" user "Ref Des/Silkscreen Bottom")
		(1 "F.Mask" user "Board Geometry/Soldermask Top")
		(3 "B.Mask" user "Board Geometry/Soldermask Bottom")
		(17 "Dwgs.User" user "User.Drawings")
		(19 "Cmts.User" user "User.Comments")
		(21 "Eco1.User" user "User.Eco1")
		(23 "Eco2.User" user "User.Eco2")
		(25 "Edge.Cuts" user "Board Geometry/Outline")
		(27 "Margin" user)
		(31 "F.CrtYd" user "Package Geometry/Place Bound Top")
		(29 "B.CrtYd" user "Package Geometry/Place Bound Bottom")
		(35 "F.Fab" user "Ref Des/Assembly Top")
		(33 "B.Fab" user "Ref Des/Assembly Bottom")
	)
	(footprint ""
		(layer "F.Cu")
		(at 114.84991 -94.84995 90)
		(property "Reference" "SU1"
			(at 0 0 90)
			(layer "F.SilkS")
			(hide yes)
			(effects
				(font
					(size 1.27 1.27)
				)
			)
		)
		(property "Value" "SAS3X24RLC1-DB-500021106-GP"
			(at -21.4503 -7.4168 90)
			(unlocked yes)
			(layer "F.Fab")
			(hide yes)
			(effects
				(font
					(size 1.016 1.016)
					(thickness 0.1524)
				)
			)
		)
		(property "Device Type" "BGA672C27H83"
			(at -21.4503 -8.9408 90)
			(unlocked yes)
			(layer "F.Fab")
			(hide yes)
			(effects
				(font
					(size 1.016 1.016)
					(thickness 0.1524)
				)
			)
		)
		(duplicate_pad_numbers_are_jumpers no)
		(pad "U15" smd circle
			(at 1.500124 3.50012 90)
			(size 0.4572 0.4572)
			(layers "F.Cu" "F.Mask" "F.Paste")
			(net "GND")
		)
		(pad "U16" smd circle
			(at 2.500122 3.50012 90)
			(size 0.4572 0.4572)
			(layers "F.Cu" "F.Mask" "F.Paste")
			(net "GND")
		)
		(pad "U17" smd circle
			(at 3.50012 3.50012 90)
			(size 0.4572 0.4572)
			(layers "F.Cu" "F.Mask" "F.Paste")
			(net "GND")
		)
		(pad "U18" smd circle
			(at 4.500118 3.50012 90)
			(size 0.4572 0.4572)
			(layers "F.Cu" "F.Mask" "F.Paste")
			(net "GND")
		)
		(pad "U19" smd circle
			(at 5.500116 3.50012 90)
			(size 0.4572 0.4572)
			(layers "F.Cu" "F.Mask" "F.Paste")
			(net "GND")
		)
		(pad "U20" smd circle
			(at 6.500114 3.50012 90)
			(size 0.4572 0.4572)
			(layers "F.Cu" "F.Mask" "F.Paste")
			(net "GND")
		)
		(pad "U21" smd circle
			(at 7.500112 3.50012 90)
			(size 0.4572 0.4572)
			(layers "F.Cu" "F.Mask" "F.Paste")
			(net "SAS_GF_EXP_RX_DN4")
		)
		(pad "U22" smd circle
			(at 8.50011 3.50012 90)
			(size 0.4572 0.4572)
			(layers "F.Cu" "F.Mask" "F.Paste")
			(net "SAS_GF_EXP_RX_DP4")
		)
		(pad "U23" smd circle
			(at 9.500108 3.50012 90)
			(size 0.4572 0.4572)
			(layers "F.Cu" "F.Mask" "F.Paste")
			(net "GB_VDDA")
		)
		(pad "U24" smd circle
			(at 10.500106 3.50012 90)
			(size 0.4572 0.4572)
			(layers "F.Cu" "F.Mask" "F.Paste")
			(net "SAS_HDD_TX0_N")
		)
		(pad "U25" smd circle
			(at 11.500104 3.50012 90)
			(size 0.4572 0.4572)
			(layers "F.Cu" "F.Mask" "F.Paste")
			(net "SAS_HDD_TX0_P")
		)
		(pad "U26" smd circle
			(at 12.500102 3.50012 90)
			(size 0.4572 0.4572)
			(layers "F.Cu" "F.Mask" "F.Paste")
			(net "GND")
		)
		(pad "V1" smd circle
			(at -12.500102 4.500118 90)
			(size 0.4572 0.4572)
			(layers "F.Cu" "F.Mask" "F.Paste")
			(net "GND")
		)
		(pad "V2" smd circle
			(at -11.500104 4.500118 90)
			(size 0.4572 0.4572)
			(layers "F.Cu" "F.Mask" "F.Paste")
			(net "GND")
		)
		(pad "V3" smd circle
			(at -10.500106 4.500118 90)
			(size 0.4572 0.4572)
			(layers "F.Cu" "F.Mask" "F.Paste")
			(net "GND")
		)
		(pad "V4" smd circle
			(at -9.500108 4.500118 90)
			(size 0.4572 0.4572)
			(layers "F.Cu" "F.Mask" "F.Paste")
			(net "TEST_MUX_44")
		)
		(pad "V5" smd circle
			(at -8.50011 4.500118 90)
			(size 0.4572 0.4572)
			(layers "F.Cu" "F.Mask" "F.Paste")
			(net "TEST_MUX_47")
		)
		(pad "V6" smd circle
			(at -7.500112 4.500118 90)
			(size 0.4572 0.4572)
			(layers "F.Cu" "F.Mask" "F.Paste")
			(net "GND")
		)
		(pad "V7" smd circle
			(at -6.500114 4.500118 90)
			(size 0.4572 0.4572)
			(layers "F.Cu" "F.Mask" "F.Paste")
			(net "GND")
		)
		(pad "V8" smd circle
			(at -5.500116 4.500118 90)
			(size 0.4572 0.4572)
			(layers "F.Cu" "F.Mask" "F.Paste")
			(net "GB_VDDH2")
		)
		(pad "V9" smd circle
			(at -4.500118 4.500118 90)
			(size 0.4572 0.4572)
			(layers "F.Cu" "F.Mask" "F.Paste")
			(net "GB_VDDH2")
		)
		(pad "V10" smd circle
			(at -3.50012 4.500118 90)
			(size 0.4572 0.4572)
			(layers "F.Cu" "F.Mask" "F.Paste")
			(net "GB_VDDH2")
		)
		(pad "V11" smd circle
			(at -2.500122 4.500118 90)
			(size 0.4572 0.4572)
			(layers "F.Cu" "F.Mask" "F.Paste")
			(net "GB_VDDH2")
		)
		(pad "V12" smd circle
			(at -1.500124 4.500118 90)
			(size 0.4572 0.4572)
			(layers "F.Cu" "F.Mask" "F.Paste")
			(net "GB_VDDH2")
		)
		(pad "V13" smd circle
			(at -0.500126 4.500118 90)
			(size 0.4572 0.4572)
			(layers "F.Cu" "F.Mask" "F.Paste")
			(net "GB_VDDH2")
		)
		(pad "V14" smd circle
			(at 0.500126 4.500118 90)
			(size 0.4572 0.4572)
			(layers "F.Cu" "F.Mask" "F.Paste")
			(net "GB_VDDH2")
		)
		(pad "V15" smd circle
			(at 1.500124 4.500118 90)
			(size 0.4572 0.4572)
			(layers "F.Cu" "F.Mask" "F.Paste")
			(net "GB_VDDH2")
		)
		(pad "V16" smd circle
			(at 2.500122 4.500118 90)
			(size 0.4572 0.4572)
			(layers "F.Cu" "F.Mask" "F.Paste")
			(net "GND")
		)
		(pad "V17" smd circle
			(at 3.50012 4.500118 90)
			(size 0.4572 0.4572)
			(layers "F.Cu" "F.Mask" "F.Paste")
			(net "GB_VDDA")
		)
		(pad "V18" smd circle
			(at 4.500118 4.500118 90)
			(size 0.4572 0.4572)
			(layers "F.Cu" "F.Mask" "F.Paste")
			(net "GND")
		)
		(pad "V19" smd circle
			(at 5.500116 4.500118 90)
			(size 0.4572 0.4572)
			(layers "F.Cu" "F.Mask" "F.Paste")
			(net "GND")
		)
		(pad "V20" smd circle
			(at 6.500114 4.500118 90)
			(size 0.4572 0.4572)
			(layers "F.Cu" "F.Mask" "F.Paste")
			(net "GB_VDDA")
		)
		(pad "V21" smd circle
			(at 7.500112 4.500118 90)
			(size 0.4572 0.4572)
			(layers "F.Cu" "F.Mask" "F.Paste")
			(net "Net_1086")
		)
		(pad "V22" smd circle
			(at 8.50011 4.500118 90)
			(size 0.4572 0.4572)
			(layers "F.Cu" "F.Mask" "F.Paste")
			(net "Net_1085")
		)
		(pad "V23" smd circle
			(at 9.500108 4.500118 90)
			(size 0.4572 0.4572)
			(layers "F.Cu" "F.Mask" "F.Paste")
			(net "GND")
		)
		(pad "V24" smd circle
			(at 10.500106 4.500118 90)
			(size 0.4572 0.4572)
			(layers "F.Cu" "F.Mask" "F.Paste")
			(net "GB_VDDA")
		)
		(pad "V25" smd circle
			(at 11.500104 4.500118 90)
			(size 0.4572 0.4572)
			(layers "F.Cu" "F.Mask" "F.Paste")
			(net "Net_1084")
		)
		(pad "V26" smd circle
			(at 12.500102 4.500118 90)
			(size 0.4572 0.4572)
			(layers "F.Cu" "F.Mask" "F.Paste")
			(net "Net_1078")
		)
		(pad "W1" smd circle
			(at -12.500102 5.500116 90)
			(size 0.4572 0.4572)
			(layers "F.Cu" "F.Mask" "F.Paste")
			(net "EXP_REF_CLK_N")
		)
		(pad "W2" smd circle
			(at -11.500104 5.500116 90)
			(size 0.4572 0.4572)
			(layers "F.Cu" "F.Mask" "F.Paste")
			(net "EXP_REF_CLK_P")
		)
		(pad "W3" smd circle
			(at -10.500106 5.500116 90)
			(size 0.4572 0.4572)
			(layers "F.Cu" "F.Mask" "F.Paste")
			(net "XTAL_VDDA18")
		)
		(pad "W4" smd circle
			(at -9.500108 5.500116 90)
			(size 0.4572 0.4572)
			(layers "F.Cu" "F.Mask" "F.Paste")
			(net "GND")
		)
		(pad "W5" smd circle
			(at -8.50011 5.500116 90)
			(size 0.4572 0.4572)
			(layers "F.Cu" "F.Mask" "F.Paste")
			(net "GND")
		)
		(pad "W6" smd circle
			(at -7.500112 5.500116 90)
			(size 0.4572 0.4572)
			(layers "F.Cu" "F.Mask" "F.Paste")
			(net "GND")
		)
		(pad "W7" smd circle
			(at -6.500114 5.500116 90)
			(size 0.4572 0.4572)
			(layers "F.Cu" "F.Mask" "F.Paste")
			(net "GND")
		)
		(pad "W8" smd circle
			(at -5.500116 5.500116 90)
			(size 0.4572 0.4572)
			(layers "F.Cu" "F.Mask" "F.Paste")
			(net "GND")
		)
		(pad "W9" smd circle
			(at -4.500118 5.500116 90)
			(size 0.4572 0.4572)
			(layers "F.Cu" "F.Mask" "F.Paste")
			(net "GND")
		)
		(pad "W10" smd circle
			(at -3.50012 5.500116 90)
			(size 0.4572 0.4572)
			(layers "F.Cu" "F.Mask" "F.Paste")
			(net "GND")
		)
		(pad "W11" smd circle
			(at -2.500122 5.500116 90)
			(size 0.4572 0.4572)
			(layers "F.Cu" "F.Mask" "F.Paste")
			(net "GND")
		)
		(pad "W12" smd circle
			(at -1.500124 5.500116 90)
			(size 0.4572 0.4572)
			(layers "F.Cu" "F.Mask" "F.Paste")
			(net "GND")
		)
		(pad "W13" smd circle
			(at -0.500126 5.500116 90)
			(size 0.4572 0.4572)
			(layers "F.Cu" "F.Mask" "F.Paste")
			(net "GND")
		)
		(pad "W14" smd circle
			(at 0.500126 5.500116 90)
			(size 0.4572 0.4572)
			(layers "F.Cu" "F.Mask" "F.Paste")
			(net "GND")
		)
		(pad "W15" smd circle
			(at 1.500124 5.500116 90)
			(size 0.4572 0.4572)
			(layers "F.Cu" "F.Mask" "F.Paste")
			(net "GND")
		)
		(pad "W16" smd circle
			(at 2.500122 5.500116 90)
			(size 0.4572 0.4572)
			(layers "F.Cu" "F.Mask" "F.Paste")
			(net "GND")
		)
		(pad "W17" smd circle
			(at 3.50012 5.500116 90)
			(size 0.4572 0.4572)
			(layers "F.Cu" "F.Mask" "F.Paste")
			(net "GND")
		)
		(pad "W18" smd circle
			(at 4.500118 5.500116 90)
			(size 0.4572 0.4572)
			(layers "F.Cu" "F.Mask" "F.Paste")
			(net "GND")
		)
		(pad "W19" smd circle
			(at 5.500116 5.500116 90)
			(size 0.4572 0.4572)
			(layers "F.Cu" "F.Mask" "F.Paste")
			(net "GND")
		)
		(pad "W20" smd circle
			(at 6.500114 5.500116 90)
			(size 0.4572 0.4572)
			(layers "F.Cu" "F.Mask" "F.Paste")
			(net "GND")
		)
		(pad "W21" smd circle
			(at 7.500112 5.500116 90)
			(size 0.4572 0.4572)
			(layers "F.Cu" "F.Mask" "F.Paste")
			(net "Net_1083")
		)
		(pad "W22" smd circle
			(at 8.50011 5.500116 90)
			(size 0.4572 0.4572)
			(layers "F.Cu" "F.Mask" "F.Paste")
			(net "Net_1082")
		)
		(pad "W23" smd circle
			(at 9.500108 5.500116 90)
			(size 0.4572 0.4572)
			(layers "F.Cu" "F.Mask" "F.Paste")
			(net "GB_VDDA")
		)
		(pad "W24" smd circle
			(at 10.500106 5.500116 90)
			(size 0.4572 0.4572)
			(layers "F.Cu" "F.Mask" "F.Paste")
			(net "Net_1081")
		)
		(pad "W25" smd circle
			(at 11.500104 5.500116 90)
			(size 0.4572 0.4572)
			(layers "F.Cu" "F.Mask" "F.Paste")
			(net "Net_1080")
		)
		(pad "W26" smd circle
			(at 12.500102 5.500116 90)
			(size 0.4572 0.4572)
			(layers "F.Cu" "F.Mask" "F.Paste")
			(net "GND")
		)
		(pad "Y1" smd circle
			(at -12.500102 6.500114 90)
			(size 0.4572 0.4572)
			(layers "F.Cu" "F.Mask" "F.Paste")
			(net "GND")
		)
		(pad "Y2" smd circle
			(at -11.500104 6.500114 90)
			(size 0.4572 0.4572)
			(layers "F.Cu" "F.Mask" "F.Paste")
			(net "GND")
		)
		(pad "Y3" smd circle
			(at -10.500106 6.500114 90)
			(size 0.4572 0.4572)
			(layers "F.Cu" "F.Mask" "F.Paste")
			(net "GND")
		)
		(pad "Y4" smd circle
			(at -9.500108 6.500114 90)
			(size 0.4572 0.4572)
			(layers "F.Cu" "F.Mask" "F.Paste")
			(net "GND")
		)
		(pad "Y5" smd circle
			(at -8.50011 6.500114 90)
			(size 0.4572 0.4572)
			(layers "F.Cu" "F.Mask" "F.Paste")
			(net "GND")
		)
		(pad "Y6" smd circle
			(at -7.500112 6.500114 90)
			(size 0.4572 0.4572)
			(layers "F.Cu" "F.Mask" "F.Paste")
			(net "GB_VDDA")
		)
		(pad "Y7" smd circle
			(at -6.500114 6.500114 90)
			(size 0.4572 0.4572)
			(layers "F.Cu" "F.Mask" "F.Paste")
			(net "GND")
		)
		(pad "Y8" smd circle
			(at -5.500116 6.500114 90)
			(size 0.4572 0.4572)
			(layers "F.Cu" "F.Mask" "F.Paste")
			(net "GB_VDDA")
		)
		(pad "Y9" smd circle
			(at -4.500118 6.500114 90)
			(size 0.4572 0.4572)
			(layers "F.Cu" "F.Mask" "F.Paste")
			(net "GND")
		)
		(pad "Y10" smd circle
			(at -3.50012 6.500114 90)
			(size 0.4572 0.4572)
			(layers "F.Cu" "F.Mask" "F.Paste")
			(net "GB_VDDA")
		)
		(pad "Y11" smd circle
			(at -2.500122 6.500114 90)
			(size 0.4572 0.4572)
			(layers "F.Cu" "F.Mask" "F.Paste")
			(net "GND")
		)
		(pad "Y12" smd circle
			(at -1.500124 6.500114 90)
			(size 0.4572 0.4572)
			(layers "F.Cu" "F.Mask" "F.Paste")
			(net "GB_VDDA")
		)
		(pad "Y13" smd circle
			(at -0.500126 6.500114 90)
			(size 0.4572 0.4572)
			(layers "F.Cu" "F.Mask" "F.Paste")
			(net "GND")
		)
		(pad "Y14" smd circle
			(at 0.500126 6.500114 90)
			(size 0.4572 0.4572)
			(layers "F.Cu" "F.Mask" "F.Paste")
			(net "GB_VDDA")
		)
		(pad "Y15" smd circle
			(at 1.500124 6.500114 90)
			(size 0.4572 0.4572)
			(layers "F.Cu" "F.Mask" "F.Paste")
			(net "GND")
		)
		(pad "Y16" smd circle
			(at 2.500122 6.500114 90)
			(size 0.4572 0.4572)
			(layers "F.Cu" "F.Mask" "F.Paste")
			(net "GB_VDDA")
		)
		(pad "Y17" smd circle
			(at 3.50012 6.500114 90)
			(size 0.4572 0.4572)
			(layers "F.Cu" "F.Mask" "F.Paste")
			(net "GND")
		)
		(pad "Y18" smd circle
			(at 4.500118 6.500114 90)
			(size 0.4572 0.4572)
			(layers "F.Cu" "F.Mask" "F.Paste")
			(net "GB_VDDA")
		)
		(pad "Y19" smd circle
			(at 5.500116 6.500114 90)
			(size 0.4572 0.4572)
			(layers "F.Cu" "F.Mask" "F.Paste")
			(net "GND")
		)
		(pad "Y20" smd circle
			(at 6.500114 6.500114 90)
			(size 0.4572 0.4572)
			(layers "F.Cu" "F.Mask" "F.Paste")
			(net "GB_VDDA")
		)
		(pad "Y21" smd circle
			(at 7.500112 6.500114 90)
			(size 0.4572 0.4572)
			(layers "F.Cu" "F.Mask" "F.Paste")
			(net "Net_1107")
		)
		(pad "Y22" smd circle
			(at 8.50011 6.500114 90)
			(size 0.4572 0.4572)
			(layers "F.Cu" "F.Mask" "F.Paste")
			(net "Net_1106")
		)
		(pad "Y23" smd circle
			(at 9.500108 6.500114 90)
			(size 0.4572 0.4572)
			(layers "F.Cu" "F.Mask" "F.Paste")
			(net "GND")
		)
		(pad "Y24" smd circle
			(at 10.500106 6.500114 90)
			(size 0.4572 0.4572)
			(layers "F.Cu" "F.Mask" "F.Paste")
			(net "GB_VDDA")
		)
		(pad "Y25" smd circle
			(at 11.500104 6.500114 90)
			(size 0.4572 0.4572)
			(layers "F.Cu" "F.Mask" "F.Paste")
			(net "Net_1105")
		)
		(pad "Y26" smd circle
			(at 12.500102 6.500114 90)
			(size 0.4572 0.4572)
			(layers "F.Cu" "F.Mask" "F.Paste")
			(net "Net_1079")
		)
	)
)
